(kicad_pcb
	(version 20241229)
	(generator "pcbnew")
	(generator_version "9.0")
	(general
		(thickness 1.62)
		(legacy_teardrops no)
	)
	(paper "A3")
	(title_block
		(title "COM Express 7 Baseboard")
		(date "2025-02-04")
		(rev "1.1.2")
		(company "Antmicro Ltd")
		(comment 1 "www.antmicro.com")
		(comment 9 "footprints 560-564 of 802")
	)
	(layers
		(0 "F.Cu" signal)
		(4 "In1.Cu" signal)
		(6 "In2.Cu" signal)
		(8 "In3.Cu" signal)
		(10 "In4.Cu" signal)
		(12 "In5.Cu" signal)
		(14 "In6.Cu" signal)
		(2 "B.Cu" signal)
		(9 "F.Adhes" user "F.Adhesive")
		(11 "B.Adhes" user "B.Adhesive")
		(13 "F.Paste" user)
		(15 "B.Paste" user)
		(5 "F.SilkS" user "F.Silkscreen")
		(7 "B.SilkS" user "B.Silkscreen")
		(1 "F.Mask" user)
		(3 "B.Mask" user)
		(17 "Dwgs.User" user "User.Drawings")
		(19 "Cmts.User" user "User.Comments")
		(21 "Eco1.User" user "User.Eco1")
		(23 "Eco2.User" user "User.Eco2")
		(25 "Edge.Cuts" user)
		(27 "Margin" user)
		(31 "F.CrtYd" user "F.Courtyard")
		(29 "B.CrtYd" user "B.Courtyard")
		(35 "F.Fab" user)
		(33 "B.Fab" user)
	)
	(footprint "antmicro-footprints:R_0402_1005Metric"
		(layer "B.Cu")
		(at 123.4 98.86 180)
		(descr "Resistor SMD 0402")
		(tags "resistor SMD 0402")
		(property "Reference" "R2"
			(at -2.4 -0.45 0)
			(layer "B.SilkS")
			(effects
				(font
					(size 0.7 0.7)
					(thickness 0.15)
				)
				(justify left bottom mirror)
			)
		)
		(property "Value" "R_0R_0402"
			(at -1.011843 -1.772047 0)
			(layer "B.Fab")
			(effects
				(font
					(size 0.7 0.7)
					(thickness 0.15)
				)
				(justify left bottom mirror)
			)
		)
		(property "Datasheet" "https://industrial.panasonic.com/cdbs/www-data/pdf/RDA0000/AOA0000C301.pdf"
			(at 0 0 180)
			(layer "F.Fab")
			(hide yes)
			(effects
				(font
					(size 1.27 1.27)
					(thickness 0.15)
				)
			)
		)
		(property "Author" "Antmicro"
			(at 246.8 197.72 0)
			(layer "B.Fab")
			(hide yes)
			(effects
				(font
					(size 1 1)
					(thickness 0.15)
				)
				(justify mirror)
			)
		)
		(property "Current" "1A"
			(at 246.8 197.72 0)
			(layer "B.Fab")
			(hide yes)
			(effects
				(font
					(size 1 1)
					(thickness 0.15)
				)
				(justify mirror)
			)
		)
		(property "License" "Apache-2.0"
			(at 246.8 197.72 0)
			(layer "B.Fab")
			(hide yes)
			(effects
				(font
					(size 1 1)
					(thickness 0.15)
				)
				(justify mirror)
			)
		)
		(property "MPN" "ERJ2GE0R00X"
			(at 246.8 197.72 0)
			(layer "B.Fab")
			(hide yes)
			(effects
				(font
					(size 1 1)
					(thickness 0.15)
				)
				(justify mirror)
			)
		)
		(property "Manufacturer" "Panasonic"
			(at 246.8 197.72 0)
			(layer "B.Fab")
			(hide yes)
			(effects
				(font
					(size 1 1)
					(thickness 0.15)
				)
				(justify mirror)
			)
		)
		(property "Public" "False"
			(at 246.8 197.72 0)
			(layer "B.Fab")
			(hide yes)
			(effects
				(font
					(size 1 1)
					(thickness 0.15)
				)
				(justify mirror)
			)
		)
		(property "Tolerance" ""
			(at 246.8 197.72 0)
			(layer "B.Fab")
			(hide yes)
			(effects
				(font
					(size 1 1)
					(thickness 0.15)
				)
				(justify mirror)
			)
		)
		(property "Val" "0R"
			(at 246.8 197.72 0)
			(layer "B.Fab")
			(hide yes)
			(effects
				(font
					(size 1 1)
					(thickness 0.15)
				)
				(justify mirror)
			)
		)
		(sheetname "2xUSB3.0+RJ45")
		(sheetfile "usb3+rj45.kicad_sch")
		(attr smd dnp)
		(fp_rect
			(start -0.925 0.47)
			(end 0.925 -0.47)
			(stroke
				(width 0.05)
				(type default)
			)
			(fill no)
			(layer "B.CrtYd")
		)
		(fp_rect
			(start -0.5 0.25)
			(end 0.5 -0.25)
			(stroke
				(width 0.15)
				(type solid)
			)
			(fill no)
			(layer "B.Fab")
		)
		(pad "1" smd roundrect
			(at -0.48 0 180)
			(size 0.59 0.64)
			(layers "B.Cu" "B.Mask" "B.Paste")
			(roundrect_rratio 0.25)
			(net 347 "/2xUSB3.0+RJ45/~{GBE0_ACT}")
			(pintype "passive")
			(teardrops
				(best_length_ratio 0.2)
				(max_length 1)
				(best_width_ratio 0.9)
				(max_width 2)
				(curved_edges yes)
				(filter_ratio 0.9)
				(enabled yes)
				(allow_two_segments yes)
				(prefer_zone_connections yes)
			)
		)
		(pad "2" smd roundrect
			(at 0.48 0 180)
			(size 0.59 0.64)
			(layers "B.Cu" "B.Mask" "B.Paste")
			(roundrect_rratio 0.25)
			(net 155 "Net-(J1A-LED_D2)")
			(pintype "passive")
			(teardrops
				(best_length_ratio 0.2)
				(max_length 1)
				(best_width_ratio 0.9)
				(max_width 2)
				(curved_edges yes)
				(filter_ratio 0.9)
				(enabled yes)
				(allow_two_segments yes)
				(prefer_zone_connections yes)
			)
		)
	)
	(footprint "antmicro-footprints:C_0402_1005Metric"
		(layer "B.Cu")
		(at 152.95 132.86)
		(descr "Capacitor SMD 0402")
		(tags "capacitor SMD 0402")
		(property "Reference" "C173"
			(at -1.8 1.4 0)
			(layer "B.SilkS")
			(effects
				(font
					(size 0.7 0.7)
					(thickness 0.15)
				)
				(justify right bottom mirror)
			)
		)
		(property "Value" "C_100n_0402"
			(at -1.022927 -2.155213 0)
			(layer "B.Fab")
			(effects
				(font
					(size 0.7 0.7)
					(thickness 0.15)
				)
				(justify right bottom mirror)
			)
		)
		(property "Datasheet" "https://www.murata.com/products/productdetail?partno=GRM155R61H104KE14%23"
			(at 0 0 0)
			(layer "F.Fab")
			(hide yes)
			(effects
				(font
					(size 1.27 1.27)
					(thickness 0.15)
				)
			)
		)
		(property "Author" "Antmicro"
			(at 0 0 0)
			(layer "B.Fab")
			(hide yes)
			(effects
				(font
					(size 1 1)
					(thickness 0.15)
				)
				(justify mirror)
			)
		)
		(property "Dielectric" "X5R"
			(at 0 0 0)
			(layer "B.Fab")
			(hide yes)
			(effects
				(font
					(size 1 1)
					(thickness 0.15)
				)
				(justify mirror)
			)
		)
		(property "License" "Apache-2.0"
			(at 0 0 0)
			(layer "B.Fab")
			(hide yes)
			(effects
				(font
					(size 1 1)
					(thickness 0.15)
				)
				(justify mirror)
			)
		)
		(property "MPN" "GRM155R61H104KE14D"
			(at 0 0 0)
			(layer "B.Fab")
			(hide yes)
			(effects
				(font
					(size 1 1)
					(thickness 0.15)
				)
				(justify mirror)
			)
		)
		(property "Manufacturer" "Murata"
			(at 0 0 0)
			(layer "B.Fab")
			(hide yes)
			(effects
				(font
					(size 1 1)
					(thickness 0.15)
				)
				(justify mirror)
			)
		)
		(property "Public" "False"
			(at 0 0 0)
			(layer "B.Fab")
			(hide yes)
			(effects
				(font
					(size 1 1)
					(thickness 0.15)
				)
				(justify mirror)
			)
		)
		(property "Val" "100n"
			(at 0 0 0)
			(layer "B.Fab")
			(hide yes)
			(effects
				(font
					(size 1 1)
					(thickness 0.15)
				)
				(justify mirror)
			)
		)
		(property "Voltage" "50V"
			(at 0 0 0)
			(layer "B.Fab")
			(hide yes)
			(effects
				(font
					(size 1 1)
					(thickness 0.15)
				)
				(justify mirror)
			)
		)
		(sheetname "KR to SFI #1")
		(sheetfile "kr_sfi.kicad_sch")
		(attr smd)
		(fp_rect
			(start -0.925 0.47)
			(end 0.925 -0.47)
			(stroke
				(width 0.05)
				(type default)
			)
			(fill no)
			(layer "B.CrtYd")
		)
		(fp_line
			(start -0.494 -0.248)
			(end 0.504 -0.248)
			(stroke
				(width 0.15)
				(type solid)
			)
			(layer "B.Fab")
		)
		(fp_line
			(start -0.494 0.25)
			(end -0.494 -0.248)
			(stroke
				(width 0.15)
				(type solid)
			)
			(layer "B.Fab")
		)
		(fp_line
			(start 0.504 -0.248)
			(end 0.504 0.25)
			(stroke
				(width 0.15)
				(type solid)
			)
			(layer "B.Fab")
		)
		(fp_line
			(start 0.504 0.25)
			(end -0.494 0.25)
			(stroke
				(width 0.15)
				(type solid)
			)
			(layer "B.Fab")
		)
		(pad "1" smd roundrect
			(at -0.48 0)
			(size 0.59 0.64)
			(layers "B.Cu" "B.Mask" "B.Paste")
			(roundrect_rratio 0.25)
			(net 1 "GND")
			(pintype "passive")
			(teardrops
				(best_length_ratio 0.2)
				(max_length 1)
				(best_width_ratio 0.9)
				(max_width 2)
				(curved_edges yes)
				(filter_ratio 0.9)
				(enabled yes)
				(allow_two_segments yes)
				(prefer_zone_connections yes)
			)
		)
		(pad "2" smd roundrect
			(at 0.48 0)
			(size 0.59 0.64)
			(layers "B.Cu" "B.Mask" "B.Paste")
			(roundrect_rratio 0.25)
			(net 74 "+1V0")
			(pintype "passive")
			(teardrops
				(best_length_ratio 0.2)
				(max_length 1)
				(best_width_ratio 0.9)
				(max_width 2)
				(curved_edges yes)
				(filter_ratio 0.9)
				(enabled yes)
				(allow_two_segments yes)
				(prefer_zone_connections yes)
			)
		)
	)
	(footprint "antmicro-footprints:C_0402_1005Metric"
		(layer "B.Cu")
		(at 134.79 141.86 180)
		(descr "Capacitor SMD 0402")
		(tags "capacitor SMD 0402")
		(property "Reference" "C196"
			(at -1.41 -1.35 0)
			(layer "B.SilkS")
			(effects
				(font
					(size 0.7 0.7)
					(thickness 0.15)
				)
				(justify left bottom mirror)
			)
		)
		(property "Value" "C_100n_0402"
			(at -1.022927 -2.155213 0)
			(layer "B.Fab")
			(effects
				(font
					(size 0.7 0.7)
					(thickness 0.15)
				)
				(justify left bottom mirror)
			)
		)
		(property "Datasheet" "https://www.murata.com/products/productdetail?partno=GRM155R61H104KE14%23"
			(at 0 0 180)
			(layer "F.Fab")
			(hide yes)
			(effects
				(font
					(size 1.27 1.27)
					(thickness 0.15)
				)
			)
		)
		(property "Author" "Antmicro"
			(at 269.58 283.72 0)
			(layer "B.Fab")
			(hide yes)
			(effects
				(font
					(size 1 1)
					(thickness 0.15)
				)
				(justify mirror)
			)
		)
		(property "Dielectric" "X5R"
			(at 269.58 283.72 0)
			(layer "B.Fab")
			(hide yes)
			(effects
				(font
					(size 1 1)
					(thickness 0.15)
				)
				(justify mirror)
			)
		)
		(property "License" "Apache-2.0"
			(at 269.58 283.72 0)
			(layer "B.Fab")
			(hide yes)
			(effects
				(font
					(size 1 1)
					(thickness 0.15)
				)
				(justify mirror)
			)
		)
		(property "MPN" "GRM155R61H104KE14D"
			(at 269.58 283.72 0)
			(layer "B.Fab")
			(hide yes)
			(effects
				(font
					(size 1 1)
					(thickness 0.15)
				)
				(justify mirror)
			)
		)
		(property "Manufacturer" "Murata"
			(at 269.58 283.72 0)
			(layer "B.Fab")
			(hide yes)
			(effects
				(font
					(size 1 1)
					(thickness 0.15)
				)
				(justify mirror)
			)
		)
		(property "Public" "False"
			(at 269.58 283.72 0)
			(layer "B.Fab")
			(hide yes)
			(effects
				(font
					(size 1 1)
					(thickness 0.15)
				)
				(justify mirror)
			)
		)
		(property "Val" "100n"
			(at 269.58 283.72 0)
			(layer "B.Fab")
			(hide yes)
			(effects
				(font
					(size 1 1)
					(thickness 0.15)
				)
				(justify mirror)
			)
		)
		(property "Voltage" "50V"
			(at 269.58 283.72 0)
			(layer "B.Fab")
			(hide yes)
			(effects
				(font
					(size 1 1)
					(thickness 0.15)
				)
				(justify mirror)
			)
		)
		(sheetname "KR to SFI #2")
		(sheetfile "kr_sfi.kicad_sch")
		(attr smd)
		(fp_rect
			(start -0.925 0.47)
			(end 0.925 -0.47)
			(stroke
				(width 0.05)
				(type default)
			)
			(fill no)
			(layer "B.CrtYd")
		)
		(fp_line
			(start 0.504 0.25)
			(end -0.494 0.25)
			(stroke
				(width 0.15)
				(type solid)
			)
			(layer "B.Fab")
		)
		(fp_line
			(start 0.504 -0.248)
			(end 0.504 0.25)
			(stroke
				(width 0.15)
				(type solid)
			)
			(layer "B.Fab")
		)
		(fp_line
			(start -0.494 0.25)
			(end -0.494 -0.248)
			(stroke
				(width 0.15)
				(type solid)
			)
			(layer "B.Fab")
		)
		(fp_line
			(start -0.494 -0.248)
			(end 0.504 -0.248)
			(stroke
				(width 0.15)
				(type solid)
			)
			(layer "B.Fab")
		)
		(pad "1" smd roundrect
			(at -0.48 0 180)
			(size 0.59 0.64)
			(layers "B.Cu" "B.Mask" "B.Paste")
			(roundrect_rratio 0.25)
			(net 1 "GND")
			(pintype "passive")
			(teardrops
				(best_length_ratio 0.2)
				(max_length 1)
				(best_width_ratio 0.9)
				(max_width 2)
				(curved_edges yes)
				(filter_ratio 0.9)
				(enabled yes)
				(allow_two_segments yes)
				(prefer_zone_connections yes)
			)
		)
		(pad "2" smd roundrect
			(at 0.48 0 180)
			(size 0.59 0.64)
			(layers "B.Cu" "B.Mask" "B.Paste")
			(roundrect_rratio 0.25)
			(net 78 "+1V8")
			(pintype "passive")
			(teardrops
				(best_length_ratio 0.2)
				(max_length 1)
				(best_width_ratio 0.9)
				(max_width 2)
				(curved_edges yes)
				(filter_ratio 0.9)
				(enabled yes)
				(allow_two_segments yes)
				(prefer_zone_connections yes)
			)
		)
	)
	(footprint "antmicro-footprints:SOD-523"
		(layer "B.Cu")
		(at 103.975 84.947)
		(property "Reference" "D10"
			(at -3.075 0.413 180)
			(layer "B.SilkS")
			(effects
				(font
					(size 0.7 0.7)
					(thickness 0.15)
				)
				(justify right bottom mirror)
			)
		)
		(property "Value" "PESD5Z5_0F"
			(at 0 -1.499 0)
			(layer "B.Fab")
			(effects
				(font
					(size 0.7 0.7)
					(thickness 0.15)
				)
				(justify right bottom mirror)
			)
		)
		(property "Datasheet" "https://assets.nexperia.com/documents/data-sheet/PESD5Z5_0.pdf"
			(at 0 0 0)
			(layer "F.Fab")
			(hide yes)
			(effects
				(font
					(size 1.27 1.27)
					(thickness 0.15)
				)
			)
		)
		(property "Author" "Antmicro"
			(at 0 0 0)
			(layer "B.Fab")
			(hide yes)
			(effects
				(font
					(size 1 1)
					(thickness 0.15)
				)
				(justify mirror)
			)
		)
		(property "License" "Apache-2.0"
			(at 0 0 0)
			(layer "B.Fab")
			(hide yes)
			(effects
				(font
					(size 1 1)
					(thickness 0.15)
				)
				(justify mirror)
			)
		)
		(property "MPN" "PESD5Z5.0F"
			(at 0 0 0)
			(layer "B.Fab")
			(hide yes)
			(effects
				(font
					(size 1 1)
					(thickness 0.15)
				)
				(justify mirror)
			)
		)
		(property "Manufacturer" "Nexperia"
			(at 0 0 0)
			(layer "B.Fab")
			(hide yes)
			(effects
				(font
					(size 1 1)
					(thickness 0.15)
				)
				(justify mirror)
			)
		)
		(property "Public" "False"
			(at 0 0 0)
			(layer "B.Fab")
			(hide yes)
			(effects
				(font
					(size 1 1)
					(thickness 0.15)
				)
				(justify mirror)
			)
		)
		(sheetname "USB-C console")
		(sheetfile "usb-c_console.kicad_sch")
		(attr smd)
		(fp_line
			(start -0.35 -0.5)
			(end -0.35 0.5)
			(stroke
				(width 0.15)
				(type solid)
			)
			(layer "B.SilkS")
		)
		(fp_rect
			(start -1 0.6)
			(end 1 -0.6)
			(stroke
				(width 0.05)
				(type solid)
			)
			(fill no)
			(layer "B.CrtYd")
		)
		(fp_line
			(start -0.652 0.425)
			(end -0.652 -0.423)
			(stroke
				(width 0.15)
				(type solid)
			)
			(layer "B.Fab")
		)
		(fp_line
			(start -0.35 -0.4)
			(end -0.35 0.4)
			(stroke
				(width 0.15)
				(type solid)
			)
			(layer "B.Fab")
		)
		(fp_line
			(start 0.65 -0.423)
			(end -0.652 -0.423)
			(stroke
				(width 0.15)
				(type solid)
			)
			(layer "B.Fab")
		)
		(fp_line
			(start 0.65 -0.423)
			(end 0.65 0.425)
			(stroke
				(width 0.15)
				(type solid)
			)
			(layer "B.Fab")
		)
		(fp_line
			(start 0.65 0.425)
			(end -0.652 0.425)
			(stroke
				(width 0.15)
				(type solid)
			)
			(layer "B.Fab")
		)
		(pad "1" smd roundrect
			(at -0.701 0)
			(size 0.5 0.6)
			(layers "B.Cu" "B.Mask" "B.Paste")
			(roundrect_rratio 0.25)
			(net 58 "/USB-C console/VBUS_FTDI")
			(pinfunction "C")
			(pintype "passive")
			(teardrops
				(best_length_ratio 0.2)
				(max_length 1)
				(best_width_ratio 0.9)
				(max_width 2)
				(curved_edges yes)
				(filter_ratio 0.9)
				(enabled yes)
				(allow_two_segments yes)
				(prefer_zone_connections yes)
			)
		)
		(pad "2" smd roundrect
			(at 0.699 0)
			(size 0.5 0.6)
			(layers "B.Cu" "B.Mask" "B.Paste")
			(roundrect_rratio 0.25)
			(net 1 "GND")
			(pinfunction "A")
			(pintype "passive")
			(teardrops
				(best_length_ratio 0.2)
				(max_length 1)
				(best_width_ratio 0.9)
				(max_width 2)
				(curved_edges yes)
				(filter_ratio 0.9)
				(enabled yes)
				(allow_two_segments yes)
				(prefer_zone_connections yes)
			)
		)
	)
	(footprint "antmicro-footprints:C_0402_1005Metric"
		(layer "B.Cu")
		(at 104.85 101.86)
		(descr "Capacitor SMD 0402")
		(tags "capacitor SMD 0402")
		(property "Reference" "C1"
			(at -2.35 0.45 0)
			(layer "B.SilkS")
			(effects
				(font
					(size 0.7 0.7)
					(thickness 0.15)
				)
				(justify right bottom mirror)
			)
		)
		(property "Value" "C_1u_0402"
			(at -1.022927 -2.155213 0)
			(layer "B.Fab")
			(effects
				(font
					(size 0.7 0.7)
					(thickness 0.15)
				)
				(justify right bottom mirror)
			)
		)
		(property "Datasheet" "https://product.tdk.com/en/search/capacitor/ceramic/mlcc/info?part_no=C1005X6S1A105K050BC"
			(at 0 0 0)
			(layer "F.Fab")
			(hide yes)
			(effects
				(font
					(size 1.27 1.27)
					(thickness 0.15)
				)
			)
		)
		(property "Author" "Antmicro"
			(at 0 0 0)
			(layer "B.Fab")
			(hide yes)
			(effects
				(font
					(size 1 1)
					(thickness 0.15)
				)
				(justify mirror)
			)
		)
		(property "Dielectric" ""
			(at 0 0 0)
			(layer "B.Fab")
			(hide yes)
			(effects
				(font
					(size 1 1)
					(thickness 0.15)
				)
				(justify mirror)
			)
		)
		(property "License" "Apache-2.0"
			(at 0 0 0)
			(layer "B.Fab")
			(hide yes)
			(effects
				(font
					(size 1 1)
					(thickness 0.15)
				)
				(justify mirror)
			)
		)
		(property "MPN" "C1005X6S1A105K050BC"
			(at 0 0 0)
			(layer "B.Fab")
			(hide yes)
			(effects
				(font
					(size 1 1)
					(thickness 0.15)
				)
				(justify mirror)
			)
		)
		(property "Manufacturer" "TDK"
			(at 0 0 0)
			(layer "B.Fab")
			(hide yes)
			(effects
				(font
					(size 1 1)
					(thickness 0.15)
				)
				(justify mirror)
			)
		)
		(property "Public" "False"
			(at 0 0 0)
			(layer "B.Fab")
			(hide yes)
			(effects
				(font
					(size 1 1)
					(thickness 0.15)
				)
				(justify mirror)
			)
		)
		(property "Val" "1u"
			(at 0 0 0)
			(layer "B.Fab")
			(hide yes)
			(effects
				(font
					(size 1 1)
					(thickness 0.15)
				)
				(justify mirror)
			)
		)
		(property "Voltage" ""
			(at 0 0 0)
			(layer "B.Fab")
			(hide yes)
			(effects
				(font
					(size 1 1)
					(thickness 0.15)
				)
				(justify mirror)
			)
		)
		(sheetname "2xUSB3.0+RJ45")
		(sheetfile "usb3+rj45.kicad_sch")
		(attr smd)
		(fp_rect
			(start -0.925 0.47)
			(end 0.925 -0.47)
			(stroke
				(width 0.05)
				(type default)
			)
			(fill no)
			(layer "B.CrtYd")
		)
		(fp_line
			(start -0.494 -0.248)
			(end 0.504 -0.248)
			(stroke
				(width 0.15)
				(type solid)
			)
			(layer "B.Fab")
		)
		(fp_line
			(start -0.494 0.25)
			(end -0.494 -0.248)
			(stroke
				(width 0.15)
				(type solid)
			)
			(layer "B.Fab")
		)
		(fp_line
			(start 0.504 -0.248)
			(end 0.504 0.25)
			(stroke
				(width 0.15)
				(type solid)
			)
			(layer "B.Fab")
		)
		(fp_line
			(start 0.504 0.25)
			(end -0.494 0.25)
			(stroke
				(width 0.15)
				(type solid)
			)
			(layer "B.Fab")
		)
		(pad "1" smd roundrect
			(at -0.48 0)
			(size 0.59 0.64)
			(layers "B.Cu" "B.Mask" "B.Paste")
			(roundrect_rratio 0.25)
			(net 1 "GND")
			(pintype "passive")
			(teardrops
				(best_length_ratio 0.2)
				(max_length 1)
				(best_width_ratio 0.9)
				(max_width 2)
				(curved_edges yes)
				(filter_ratio 0.9)
				(enabled yes)
				(allow_two_segments yes)
				(prefer_zone_connections yes)
			)
		)
		(pad "2" smd roundrect
			(at 0.48 0)
			(size 0.59 0.64)
			(layers "B.Cu" "B.Mask" "B.Paste")
			(roundrect_rratio 0.25)
			(net 42 "/2xUSB3.0+RJ45/P1_VBUS")
			(pintype "passive")
			(teardrops
				(best_length_ratio 0.2)
				(max_length 1)
				(best_width_ratio 0.9)
				(max_width 2)
				(curved_edges yes)
				(filter_ratio 0.9)
				(enabled yes)
				(allow_two_segments yes)
				(prefer_zone_connections yes)
			)
		)
	)
)
